FILE_TYPE = CONNECTIVITY;
{Allegro Design Entry HDL 17.4-2019 S026 (4007227) 1/17/2022}
"PAGE_NUMBER" = 433;
0"NC";
1"P0V9_CPU0_RT3_2A\g";
2"GND\g";
3"P0V9_CPU0_RT_2D\g";
4"GND\g";
5"P1V8_CPU0_RT_1D\g";
6"GND\g";
7"P1V8_CPU0_RT3_1A\g";
8"GND\g";
9"GND\g";
10"GND\g";
11"P0V9_CPU0_RT3_2A_2D\g";
12"GND\g";
13"P1V8_CPU0_RT3_1A_1D\g";
%"Q_RES"
"1","(-7850,3750)","0","pure_quanta","I1";
;
LOCATION"R1087"
SEC"1"
WATTAGE"1/16W"
PACK_TYPE"0402LF"
VALUE"0"
MATERIAL"EMPTY"
TOLERANCE"5%"
SEC_TYPE"0402LF"
CDS_LIB"pure_quanta"
PART_NUMBER"CS00002JB13";
"B"
$PN"2"7;
"A"
$PN"1"13;
%"Q_INDUCTOR"
"1","(-7925,4650)","0","pure_quanta","I10";
;
LOCATION"L22"
$SEC"1"
CDS_SEC"1"
PACK_TYPE"SMLF"
VALUE"BLM21SN300SN1D/5A"
MATERIAL"IND"
NEEDS_NO_SIZE"TRUE"
CDS_LIB"pure_quanta"
PART_NUMBER"CX300SN1000";
"1"
$PN"1"5;
"2"
$PN"2"7;
%"P1V0"
"1","(-8300,5475)","0","pure_quanta_power","I11";
;
HDL_POWER"P1V8_CPU0_RT_1D"
CDS_LIB"pure_quanta_power";
"A"5;
%"Q_CAP"
"1","(-7350,4375)","0","pure_quanta","I12";
;
LOCATION"C991"
$SEC"1"
CDS_SEC"1"
TOLERANCE"20%"
VALUE"100UF"
PACK_TYPE"C0805"
VOLTAGE"4V"
MATERIAL"X6S"
CDS_LIB"pure_quanta"
PART_NUMBER"CH710KMEA01";
"B"
$PN"2"8;
"A"
$PN"1"7;
%"Q_CAP"
"1","(-7125,4375)","0","pure_quanta","I13";
;
LOCATION"C993"
$SEC"1"
CDS_SEC"1"
PACK_TYPE"C0402"
TOLERANCE"20%"
MATERIAL"X6S"
VALUE"22UF"
VOLTAGE"4V"
CDS_LIB"pure_quanta"
PART_NUMBER"CH622KMEB02";
"B"
$PN"2"8;
"A"
$PN"1"7;
%"P1V0"
"1","(-7450,4850)","0","pure_quanta_power","I14";
;
HDL_POWER"P1V8_CPU0_RT3_1A"
CDS_LIB"pure_quanta_power";
"A"7;
%"Q_CAP"
"1","(-6925,4375)","0","pure_quanta","I15";
;
LOCATION"C995"
$SEC"1"
CDS_SEC"1"
PACK_TYPE"C0402"
TOLERANCE"20%"
MATERIAL"X6S"
VALUE"10UF"
VOLTAGE"6.3V"
CDS_LIB"pure_quanta"
PART_NUMBER"CH6101MEB01";
"B"
$PN"2"8;
"A"
$PN"1"7;
%"Q_CAP"
"1","(-6725,4375)","0","pure_quanta","I16";
;
LOCATION"C996"
$SEC"1"
CDS_SEC"1"
VOLTAGE"6.3V"
VALUE"4.7UF"
MATERIAL"X6S"
PACK_TYPE"0402"
TOLERANCE"20%"
CDS_LIB"pure_quanta"
PART_NUMBER"CH5471MEB01";
"B"
$PN"2"8;
"A"
$PN"1"7;
%"Q_CAP"
"1","(-6500,4375)","0","pure_quanta","I17";
;
LOCATION"C998"
$SEC"1"
CDS_SEC"1"
PACK_TYPE"0201"
MATERIAL"X6S"
VALUE"1UF"
VOLTAGE"4V"
TOLERANCE"20%"
CDS_LIB"pure_quanta"
PART_NUMBER"CH-10KMEE00";
"B"
$PN"2"8;
"A"
$PN"1"7;
%"UNIVERSAL_GND"
"1","(-6525,4900)","0","pure_quanta_power","I18";
;
CDS_LIB"pure_quanta_power"
HDL_POWER"GND";
"A"6;
%"Q_CAP"
"1","(-7200,5200)","0","pure_quanta","I19";
;
LOCATION"C990"
$SEC"1"
CDS_SEC"1"
PACK_TYPE"C0805"
MATERIAL"X6S"
TOLERANCE"20%"
VALUE"100UF"
VOLTAGE"4V"
CDS_LIB"pure_quanta"
PART_NUMBER"CH710KMEA01";
"B"
$PN"2"6;
"A"
$PN"1"5;
%"Q_RES"
"1","(-7850,3950)","0","pure_quanta","I2";
;
LOCATION"R1086"
SEC"1"
MATERIAL"EMPTY"
WATTAGE"1/16W"
PACK_TYPE"0402LF"
TOLERANCE"5%"
VALUE"0"
CDS_LIB"pure_quanta"
SEC_TYPE"0402LF"
PART_NUMBER"CS00002JB13";
"B"
$PN"2"7;
"A"
$PN"1"13;
%"Q_CAP"
"1","(-6950,5200)","0","pure_quanta","I20";
;
LOCATION"C992"
$SEC"1"
CDS_SEC"1"
PACK_TYPE"C0402"
VALUE"22UF"
TOLERANCE"20%"
MATERIAL"X6S"
VOLTAGE"4V"
CDS_LIB"pure_quanta"
PART_NUMBER"CH622KMEB02";
"B"
$PN"2"6;
"A"
$PN"1"5;
%"Q_CAP"
"1","(-6700,5175)","0","pure_quanta","I21";
;
LOCATION"C994"
$SEC"1"
CDS_SEC"1"
PACK_TYPE"C0402"
VALUE"10UF"
VOLTAGE"6.3V"
TOLERANCE"20%"
MATERIAL"X6S"
CDS_LIB"pure_quanta"
PART_NUMBER"CH6101MEB01";
"B"
$PN"2"6;
"A"
$PN"1"5;
%"Q_CAP"
"1","(-6450,5175)","0","pure_quanta","I22";
;
LOCATION"C997"
$SEC"1"
CDS_SEC"1"
VOLTAGE"6.3V"
VALUE"4.7UF"
PACK_TYPE"0402"
MATERIAL"X6S"
TOLERANCE"20%"
CDS_LIB"pure_quanta"
PART_NUMBER"CH5471MEB01";
"B"
$PN"2"6;
"A"
$PN"1"5;
%"UNIVERSAL_GND"
"1","(-6300,4050)","0","pure_quanta_power","I23";
;
CDS_LIB"pure_quanta_power"
HDL_POWER"GND";
"A"8;
%"Q_CAP"
"1","(-6300,4375)","0","pure_quanta","I24";
;
LOCATION"C1000"
$SEC"1"
CDS_SEC"1"
PACK_TYPE"0201"
TOLERANCE"20%"
MATERIAL"X6S"
VOLTAGE"4V"
VALUE"1UF"
CDS_LIB"pure_quanta"
PART_NUMBER"CH-10KMEE00";
"B"
$PN"2"8;
"A"
$PN"1"7;
%"Q_CAP"
"1","(-6075,4375)","0","pure_quanta","I25";
;
LOCATION"C1001"
$SEC"1"
CDS_SEC"1"
VALUE"0.1UF"
TOLERANCE"10%"
VOLTAGE"10V"
PACK_TYPE"C0201"
MATERIAL"X7S"
CDS_LIB"pure_quanta"
PART_NUMBER"CH4102K6E00";
"B"
$PN"2"8;
"A"
$PN"1"7;
%"Q_CAP"
"1","(-5825,4375)","0","pure_quanta","I26";
;
LOCATION"C1003"
$SEC"1"
CDS_SEC"1"
TOLERANCE"10%"
VOLTAGE"10V"
PACK_TYPE"C0201"
VALUE"0.1UF"
MATERIAL"X7S"
CDS_LIB"pure_quanta"
PART_NUMBER"CH4102K6E00";
"B"
$PN"2"8;
"A"
$PN"1"7;
%"Q_CAP"
"1","(-5575,4375)","0","pure_quanta","I27";
;
LOCATION"C1004"
$SEC"1"
CDS_SEC"1"
TOLERANCE"10%"
VALUE"0.1UF"
VOLTAGE"10V"
PACK_TYPE"C0201"
MATERIAL"X7S"
CDS_LIB"pure_quanta"
PART_NUMBER"CH4102K6E00";
"B"
$PN"2"8;
"A"
$PN"1"7;
%"Q_CAP"
"1","(-5300,4375)","0","pure_quanta","I28";
;
LOCATION"C1005"
$SEC"1"
CDS_SEC"1"
PACK_TYPE"C0201"
VALUE"0.1UF"
VOLTAGE"10V"
TOLERANCE"10%"
MATERIAL"X7S"
CDS_LIB"pure_quanta"
PART_NUMBER"CH4102K6E00";
"B"
$PN"2"8;
"A"
$PN"1"7;
%"VCC_CORE"
"1","(-4450,6150)","0","pure_quanta_power","I29";
;
HDL_POWER"P0V9_CPU0_RT_2D"
CDS_LIB"pure_quanta_power";
"A"3;
%"UNIVERSAL_GND"
"1","(-6650,2875)","0","pure_quanta_power","I3";
;
CDS_LIB"pure_quanta_power"
HDL_POWER"GND";
"A"10;
%"Q_CAP"
"1","(-3175,1325)","0","pure_quanta","I30";
;
LOCATION"C1014"
$SEC"1"
CDS_SEC"1"
TOLERANCE"10%"
VOLTAGE"10V"
VALUE"0.1UF"
PACK_TYPE"C0201"
MATERIAL"X7S"
CDS_LIB"pure_quanta"
PART_NUMBER"CH4102K6E00";
"B"
$PN"2"12;
"A"
$PN"1"11;
%"VCC_CORE"
"1","(-3300,1850)","0","pure_quanta_power","I32";
;
HDL_POWER"P0V9_CPU0_RT3_2A_2D"
CDS_LIB"pure_quanta_power";
"A"11;
%"UNIVERSAL_GND"
"1","(-2475,1000)","0","pure_quanta_power","I34";
;
CDS_LIB"pure_quanta_power"
HDL_POWER"GND";
"A"12;
%"Q_CAP"
"1","(-2375,1325)","0","pure_quanta","I35";
;
LOCATION"C1021"
$SEC"1"
CDS_SEC"1"
VALUE"0.1UF"
TOLERANCE"10%"
VOLTAGE"10V"
MATERIAL"X7S"
PACK_TYPE"C0201"
CDS_LIB"pure_quanta"
PART_NUMBER"CH4102K6E00";
"B"
$PN"2"12;
"A"
$PN"1"11;
%"Q_RES"
"1","(-4075,2675)","0","pure_quanta","I36";
;
LOCATION"R1095"
$SEC"1"
CDS_SEC"1"
MATERIAL"CHIP"
VALUE"0"
TOLERANCE"5%"
WATTAGE"1/4W"
PACK_TYPE"0603LF"
CDS_LIB"pure_quanta"
PART_NUMBER"CS00006J900";
"B"
$PN"2"1;
"A"
$PN"1"11;
%"Q_CAP"
"1","(-3625,3125)","0","pure_quanta","I37";
;
LOCATION"C1024"
$SEC"1"
CDS_SEC"1"
VALUE"1UF"
PACK_TYPE"0201"
MATERIAL"X6S"
TOLERANCE"20%"
VOLTAGE"4V"
CDS_LIB"pure_quanta"
PART_NUMBER"CH-10KMEE00";
"B"
$PN"2"2;
"A"
$PN"1"1;
%"Q_CAP"
"1","(-3400,3125)","0","pure_quanta","I38";
;
LOCATION"C1027"
$SEC"1"
CDS_SEC"1"
TOLERANCE"20%"
MATERIAL"X6S"
VALUE"1UF"
VOLTAGE"4V"
PACK_TYPE"0201"
CDS_LIB"pure_quanta"
PART_NUMBER"CH-10KMEE00";
"B"
$PN"2"2;
"A"
$PN"1"1;
%"Q_CAP"
"1","(-3625,3750)","0","pure_quanta","I39";
;
LOCATION"C1023"
$SEC"1"
CDS_SEC"1"
VALUE"10UF"
PACK_TYPE"C0402"
MATERIAL"X6S"
VOLTAGE"6.3V"
TOLERANCE"20%"
CDS_LIB"pure_quanta"
PART_NUMBER"CH6101MEB01";
"B"
$PN"2"2;
"A"
$PN"1"1;
%"P1V0"
"1","(-7050,3675)","0","pure_quanta_power","I4";
;
HDL_POWER"P1V8_CPU0_RT3_1A_1D"
CDS_LIB"pure_quanta_power";
"A"13;
%"Q_CAP"
"1","(-3400,3750)","0","pure_quanta","I40";
;
LOCATION"C1036"
$SEC"1"
CDS_SEC"1"
VOLTAGE"6.3V"
VALUE"10UF"
TOLERANCE"20%"
MATERIAL"X6S"
PACK_TYPE"C0402"
CDS_LIB"pure_quanta"
PART_NUMBER"CH6101MEB01";
"B"
$PN"2"2;
"A"
$PN"1"1;
%"Q_CAP"
"1","(-3350,2425)","0","pure_quanta","I41";
;
LOCATION"C1010"
$SEC"1"
CDS_SEC"1"
TOLERANCE"10%"
MATERIAL"X7S"
PACK_TYPE"C0201"
VALUE"0.1UF"
VOLTAGE"10V"
CDS_LIB"pure_quanta"
PART_NUMBER"CH4102K6E00";
"B"
$PN"2"9;
"A"
$PN"1"1;
%"Q_CAP"
"1","(-3050,2425)","0","pure_quanta","I42";
;
LOCATION"C1052"
$SEC"1"
CDS_SEC"1"
PACK_TYPE"C0201"
TOLERANCE"10%"
VALUE"0.1UF"
MATERIAL"X7S"
VOLTAGE"10V"
CDS_LIB"pure_quanta"
PART_NUMBER"CH4102K6E00";
"B"
$PN"2"9;
"A"
$PN"1"1;
%"Q_CAP"
"1","(-2825,2425)","0","pure_quanta","I43";
;
LOCATION"C1055"
$SEC"1"
CDS_SEC"1"
PACK_TYPE"C0201"
VALUE"0.1UF"
VOLTAGE"10V"
TOLERANCE"10%"
MATERIAL"X7S"
CDS_LIB"pure_quanta"
PART_NUMBER"CH4102K6E00";
"B"
$PN"2"9;
"A"
$PN"1"1;
%"Q_CAP"
"1","(-2575,2425)","0","pure_quanta","I44";
;
LOCATION"C1035"
$SEC"1"
CDS_SEC"1"
PACK_TYPE"C0201"
VALUE"0.1UF"
VOLTAGE"10V"
MATERIAL"X7S"
TOLERANCE"10%"
CDS_LIB"pure_quanta"
PART_NUMBER"CH4102K6E00";
"B"
$PN"2"9;
"A"
$PN"1"1;
%"Q_CAP"
"1","(-3150,3125)","0","pure_quanta","I45";
;
LOCATION"C1031"
$SEC"1"
CDS_SEC"1"
TOLERANCE"20%"
MATERIAL"X6S"
VALUE"1UF"
PACK_TYPE"0201"
VOLTAGE"4V"
CDS_LIB"pure_quanta"
PART_NUMBER"CH-10KMEE00";
"B"
$PN"2"2;
"A"
$PN"1"1;
%"Q_CAP"
"1","(-2925,3125)","0","pure_quanta","I46";
;
LOCATION"C1006"
$SEC"1"
CDS_SEC"1"
PACK_TYPE"0201"
VOLTAGE"4V"
VALUE"1UF"
TOLERANCE"20%"
MATERIAL"X6S"
CDS_LIB"pure_quanta"
PART_NUMBER"CH-10KMEE00";
"B"
$PN"2"2;
"A"
$PN"1"1;
%"Q_CAP"
"1","(-2950,3750)","0","pure_quanta","I47";
;
LOCATION"C1034"
$SEC"1"
CDS_SEC"1"
VOLTAGE"6.3V"
VALUE"4.7UF"
TOLERANCE"20%"
PACK_TYPE"0402"
MATERIAL"X6S"
CDS_LIB"pure_quanta"
PART_NUMBER"CH5471MEB01";
"B"
$PN"2"2;
"A"
$PN"1"1;
%"Q_CAP"
"1","(-2675,3125)","0","pure_quanta","I48";
;
LOCATION"C1039"
$SEC"1"
CDS_SEC"1"
PACK_TYPE"0201"
VALUE"1UF"
MATERIAL"X6S"
VOLTAGE"4V"
TOLERANCE"20%"
CDS_LIB"pure_quanta"
PART_NUMBER"CH-10KMEE00";
"B"
$PN"2"2;
"A"
$PN"1"1;
%"Q_CAP"
"1","(-2450,3100)","0","pure_quanta","I49";
;
LOCATION"C1015"
$SEC"1"
CDS_SEC"1"
MATERIAL"X6S"
TOLERANCE"20%"
VALUE"1UF"
VOLTAGE"4V"
PACK_TYPE"0201"
CDS_LIB"pure_quanta"
PART_NUMBER"CH-10KMEE00";
"B"
$PN"2"2;
"A"
$PN"1"1;
%"Q_CAP"
"1","(-6925,3300)","0","pure_quanta","I5";
;
LOCATION"C999"
$SEC"1"
CDS_SEC"1"
VALUE"1UF"
MATERIAL"X6S"
PACK_TYPE"0201"
TOLERANCE"20%"
VOLTAGE"4V"
CDS_LIB"pure_quanta"
PART_NUMBER"CH-10KMEE00";
"B"
$PN"2"10;
"A"
$PN"1"13;
%"Q_CAP"
"1","(-2700,3750)","0","pure_quanta","I50";
;
LOCATION"C1054"
$SEC"1"
CDS_SEC"1"
TOLERANCE"20%"
MATERIAL"X6S"
PACK_TYPE"0402"
VOLTAGE"6.3V"
VALUE"4.7UF"
CDS_LIB"pure_quanta"
PART_NUMBER"CH5471MEB01";
"B"
$PN"2"2;
"A"
$PN"1"1;
%"Q_CAP"
"1","(-2475,3750)","0","pure_quanta","I51";
;
LOCATION"C1056"
$SEC"1"
CDS_SEC"1"
VOLTAGE"6.3V"
PACK_TYPE"0402"
TOLERANCE"20%"
VALUE"4.7UF"
MATERIAL"X6S"
CDS_LIB"pure_quanta"
PART_NUMBER"CH5471MEB01";
"B"
$PN"2"2;
"A"
$PN"1"1;
%"Q_CAP"
"1","(-2325,2425)","0","pure_quanta","I52";
;
LOCATION"C1008"
$SEC"1"
CDS_SEC"1"
MATERIAL"X7S"
PACK_TYPE"C0201"
TOLERANCE"10%"
VOLTAGE"10V"
VALUE"0.1UF"
CDS_LIB"pure_quanta"
PART_NUMBER"CH4102K6E00";
"B"
$PN"2"9;
"A"
$PN"1"1;
%"Q_CAP"
"1","(-2050,2425)","0","pure_quanta","I53";
;
LOCATION"C1011"
$SEC"1"
CDS_SEC"1"
PACK_TYPE"C0201"
MATERIAL"X7S"
VOLTAGE"10V"
VALUE"0.1UF"
TOLERANCE"10%"
CDS_LIB"pure_quanta"
PART_NUMBER"CH4102K6E00";
"B"
$PN"2"9;
"A"
$PN"1"1;
%"Q_CAP"
"1","(-1775,2425)","0","pure_quanta","I54";
;
LOCATION"C1043"
$SEC"1"
CDS_SEC"1"
MATERIAL"X7S"
VALUE"0.1UF"
VOLTAGE"10V"
TOLERANCE"10%"
PACK_TYPE"C0201"
CDS_LIB"pure_quanta"
PART_NUMBER"CH4102K6E00";
"B"
$PN"2"9;
"A"
$PN"1"1;
%"UNIVERSAL_GND"
"1","(-1525,2000)","0","pure_quanta_power","I55";
;
CDS_LIB"pure_quanta_power"
HDL_POWER"GND";
"A"9;
%"Q_CAP"
"1","(-1525,2425)","0","pure_quanta","I56";
;
LOCATION"C1047"
$SEC"1"
CDS_SEC"1"
MATERIAL"X7S"
VOLTAGE"10V"
TOLERANCE"10%"
PACK_TYPE"C0201"
VALUE"0.1UF"
CDS_LIB"pure_quanta"
PART_NUMBER"CH4102K6E00";
"B"
$PN"2"9;
"A"
$PN"1"1;
%"Q_CAP"
"1","(-2225,3100)","0","pure_quanta","I57";
;
LOCATION"C1019"
$SEC"1"
CDS_SEC"1"
VOLTAGE"4V"
VALUE"1UF"
TOLERANCE"20%"
MATERIAL"X6S"
PACK_TYPE"0201"
CDS_LIB"pure_quanta"
PART_NUMBER"CH-10KMEE00";
"B"
$PN"2"2;
"A"
$PN"1"1;
%"Q_CAP"
"1","(-2250,3750)","0","pure_quanta","I59";
;
LOCATION"C1046"
$SEC"1"
CDS_SEC"1"
VALUE"1UF"
VOLTAGE"4V"
MATERIAL"X6S"
TOLERANCE"20%"
PACK_TYPE"0201"
CDS_LIB"pure_quanta"
PART_NUMBER"CH-10KMEE00";
"B"
$PN"2"2;
"A"
$PN"1"1;
%"Q_CAP"
"1","(-6650,3275)","0","pure_quanta","I6";
;
LOCATION"C1002"
$SEC"1"
CDS_SEC"1"
VOLTAGE"10V"
TOLERANCE"10%"
MATERIAL"X7S"
PACK_TYPE"C0201"
VALUE"0.1UF"
CDS_LIB"pure_quanta"
PART_NUMBER"CH4102K6E00";
"B"
$PN"2"10;
"A"
$PN"1"13;
%"Q_CAP"
"1","(-2025,3750)","0","pure_quanta","I60";
;
LOCATION"C1050"
$SEC"1"
CDS_SEC"1"
VALUE"1UF"
VOLTAGE"4V"
TOLERANCE"20%"
MATERIAL"X6S"
PACK_TYPE"0201"
CDS_LIB"pure_quanta"
PART_NUMBER"CH-10KMEE00";
"B"
$PN"2"2;
"A"
$PN"1"1;
%"Q_CAP"
"1","(-1800,3750)","0","pure_quanta","I62";
;
LOCATION"C1013"
$SEC"1"
CDS_SEC"1"
VOLTAGE"4V"
TOLERANCE"20%"
PACK_TYPE"0201"
VALUE"1UF"
MATERIAL"X6S"
CDS_LIB"pure_quanta"
PART_NUMBER"CH-10KMEE00";
"B"
$PN"2"2;
"A"
$PN"1"1;
%"Q_CAP"
"1","(-1550,3750)","0","pure_quanta","I63";
;
LOCATION"C1017"
$SEC"1"
CDS_SEC"1"
PACK_TYPE"0201"
TOLERANCE"20%"
VOLTAGE"4V"
VALUE"1UF"
MATERIAL"X6S"
CDS_LIB"pure_quanta"
PART_NUMBER"CH-10KMEE00";
"B"
$PN"2"2;
"A"
$PN"1"1;
%"UNIVERSAL_GND"
"1","(-1025,2700)","0","pure_quanta_power","I64";
;
CDS_LIB"pure_quanta_power"
HDL_POWER"GND";
"A"2;
%"Q_INDUCTOR"
"1","(-3975,4650)","0","pure_quanta","I65";
;
LOCATION"L23"
$SEC"1"
CDS_SEC"1"
VALUE"100NH/16A"
PACK_TYPE"SMLF"
MATERIAL"IND"
CDS_LIB"pure_quanta"
NEEDS_NO_SIZE"TRUE"
PART_NUMBER"CV+10G0MZ04";
"1"
$PN"1"3;
"2"
$PN"2"1;
%"Q_CAP"
"1","(-3625,4375)","0","pure_quanta","I66";
;
LOCATION"C1022"
$SEC"1"
CDS_SEC"1"
TOLERANCE"20%"
MATERIAL"X6S"
VALUE"100UF"
VOLTAGE"4V"
PACK_TYPE"C0805"
CDS_LIB"pure_quanta"
PART_NUMBER"CH710KMEA01";
"B"
$PN"2"2;
"A"
$PN"1"1;
%"Q_CAP"
"1","(-3400,4375)","0","pure_quanta","I67";
;
LOCATION"C1025"
$SEC"1"
CDS_SEC"1"
VALUE"100UF"
TOLERANCE"20%"
VOLTAGE"4V"
MATERIAL"X6S"
PACK_TYPE"C0805"
CDS_LIB"pure_quanta"
PART_NUMBER"CH710KMEA01";
"B"
$PN"2"2;
"A"
$PN"1"1;
%"VCC_CORE"
"1","(-3625,5025)","0","pure_quanta_power","I68";
;
HDL_POWER"P0V9_CPU0_RT3_2A"
CDS_LIB"pure_quanta_power";
"A"1;
%"Q_CAP"
"1","(-3575,5650)","0","pure_quanta","I69";
;
LOCATION"C1028"
$SEC"1"
CDS_SEC"1"
PACK_TYPE"C0805"
TOLERANCE"20%"
MATERIAL"X6S"
VOLTAGE"4V"
VALUE"100UF"
CDS_LIB"pure_quanta"
PART_NUMBER"CH710KMEA01";
"B"
$PN"2"4;
"A"
$PN"1"3;
%"Q_RES"
"2","(-4450,2950)","2","pure_quanta","I7";
;
LOCATION"R1094"
$SEC"1"
CDS_SEC"1"
PACK_TYPE"0603LF"
TOLERANCE"5%"
WATTAGE"1/4W"
MATERIAL"EMPTY"
VALUE"0"
CDS_LIB"pure_quanta"
PART_NUMBER"CS00006J900";
"A"
$PN"1"3;
"B"
$PN"2"11;
%"Q_CAP"
"1","(-3175,4375)","0","pure_quanta","I70";
;
LOCATION"C1029"
$SEC"1"
CDS_SEC"1"
TOLERANCE"20%"
PACK_TYPE"C0805"
MATERIAL"X6S"
VOLTAGE"4V"
VALUE"100UF"
CDS_LIB"pure_quanta"
PART_NUMBER"CH710KMEA01";
"B"
$PN"2"2;
"A"
$PN"1"1;
%"Q_CAP"
"1","(-2950,4375)","0","pure_quanta","I71";
;
LOCATION"C1033"
$SEC"1"
CDS_SEC"1"
PACK_TYPE"C0805"
MATERIAL"X6S"
TOLERANCE"20%"
VOLTAGE"4V"
VALUE"100UF"
CDS_LIB"pure_quanta"
PART_NUMBER"CH710KMEA01";
"B"
$PN"2"2;
"A"
$PN"1"1;
%"Q_CAP"
"1","(-2700,4375)","0","pure_quanta","I72";
;
LOCATION"C1026"
$SEC"1"
CDS_SEC"1"
VALUE"22UF"
VOLTAGE"4V"
TOLERANCE"20%"
MATERIAL"X6S"
PACK_TYPE"C0402"
CDS_LIB"pure_quanta"
PART_NUMBER"CH622KMEB02";
"B"
$PN"2"2;
"A"
$PN"1"1;
%"Q_CAP"
"1","(-2975,5625)","0","pure_quanta","I73";
;
LOCATION"C1044"
$SEC"1"
CDS_SEC"1"
TOLERANCE"20%"
MATERIAL"X6S"
VOLTAGE"6.3V"
VALUE"10UF"
PACK_TYPE"C0402"
CDS_LIB"pure_quanta"
PART_NUMBER"CH6101MEB01";
"B"
$PN"2"4;
"A"
$PN"1"3;
%"Q_CAP"
"1","(-3300,5650)","0","pure_quanta","I74";
;
LOCATION"C1032"
$SEC"1"
CDS_SEC"1"
MATERIAL"X6S"
TOLERANCE"20%"
PACK_TYPE"C0402"
VALUE"22UF"
VOLTAGE"4V"
CDS_LIB"pure_quanta"
PART_NUMBER"CH622KMEB02";
"B"
$PN"2"4;
"A"
$PN"1"3;
%"Q_CAP"
"1","(-2675,5625)","0","pure_quanta","I75";
;
LOCATION"C1038"
$SEC"1"
CDS_SEC"1"
PACK_TYPE"0402"
VALUE"4.7UF"
TOLERANCE"20%"
VOLTAGE"6.3V"
MATERIAL"X6S"
CDS_LIB"pure_quanta"
PART_NUMBER"CH5471MEB01";
"B"
$PN"2"4;
"A"
$PN"1"3;
%"Q_CAP"
"1","(-2375,5625)","0","pure_quanta","I76";
;
LOCATION"C1016"
$SEC"1"
CDS_SEC"1"
PACK_TYPE"0201"
TOLERANCE"20%"
VOLTAGE"4V"
VALUE"1UF"
MATERIAL"X6S"
CDS_LIB"pure_quanta"
PART_NUMBER"CH-10KMEE00";
"B"
$PN"2"4;
"A"
$PN"1"3;
%"Q_CAP"
"1","(-2250,4375)","0","pure_quanta","I77";
;
LOCATION"C1030"
$SEC"1"
CDS_SEC"1"
VALUE"22UF"
TOLERANCE"20%"
VOLTAGE"4V"
MATERIAL"X6S"
PACK_TYPE"C0402"
CDS_LIB"pure_quanta"
PART_NUMBER"CH622KMEB02";
"B"
$PN"2"2;
"A"
$PN"1"1;
%"Q_CAP"
"1","(-2025,4375)","0","pure_quanta","I78";
;
LOCATION"C1041"
$SEC"1"
CDS_SEC"1"
PACK_TYPE"C0402"
TOLERANCE"20%"
VALUE"22UF"
VOLTAGE"4V"
MATERIAL"X6S"
CDS_LIB"pure_quanta"
PART_NUMBER"CH622KMEB02";
"B"
$PN"2"2;
"A"
$PN"1"1;
%"Q_CAP"
"1","(-1725,4375)","0","pure_quanta","I79";
;
LOCATION"C1037"
$SEC"1"
CDS_SEC"1"
PACK_TYPE"C0402"
MATERIAL"X6S"
TOLERANCE"20%"
VOLTAGE"6.3V"
VALUE"10UF"
CDS_LIB"pure_quanta"
PART_NUMBER"CH6101MEB01";
"B"
$PN"2"2;
"A"
$PN"1"1;
%"Q_CAP"
"1","(-1425,4375)","0","pure_quanta","I80";
;
LOCATION"C1049"
$SEC"1"
CDS_SEC"1"
PACK_TYPE"C0402"
VOLTAGE"6.3V"
MATERIAL"X6S"
TOLERANCE"20%"
VALUE"10UF"
CDS_LIB"pure_quanta"
PART_NUMBER"CH6101MEB01";
"B"
$PN"2"2;
"A"
$PN"1"1;
%"Q_CAP"
"1","(-2075,5600)","0","pure_quanta","I81";
;
LOCATION"C1007"
$SEC"1"
CDS_SEC"1"
TOLERANCE"10%"
MATERIAL"X7S"
VALUE"0.1UF"
VOLTAGE"10V"
PACK_TYPE"C0201"
CDS_LIB"pure_quanta"
PART_NUMBER"CH4102K6E00";
"B"
$PN"2"4;
"A"
$PN"1"3;
%"Q_CAP"
"1","(-1800,5600)","0","pure_quanta","I82";
;
LOCATION"C1009"
$SEC"1"
CDS_SEC"1"
VALUE"0.1UF"
VOLTAGE"10V"
TOLERANCE"10%"
MATERIAL"X7S"
PACK_TYPE"C0201"
CDS_LIB"pure_quanta"
PART_NUMBER"CH4102K6E00";
"B"
$PN"2"4;
"A"
$PN"1"3;
%"UNIVERSAL_GND"
"1","(-1350,5200)","0","pure_quanta_power","I83";
;
CDS_LIB"pure_quanta_power"
HDL_POWER"GND";
"A"4;
%"Q_CAP"
"1","(-1550,5600)","0","pure_quanta","I84";
;
LOCATION"C1012"
$SEC"1"
CDS_SEC"1"
VALUE"0.1UF"
MATERIAL"X7S"
PACK_TYPE"C0201"
VOLTAGE"10V"
TOLERANCE"10%"
CDS_LIB"pure_quanta"
PART_NUMBER"CH4102K6E00";
"B"
$PN"2"4;
"A"
$PN"1"3;
%"Q_CAP"
"1","(-1275,5600)","0","pure_quanta","I85";
;
LOCATION"C1048"
$SEC"1"
CDS_SEC"1"
VOLTAGE"10V"
TOLERANCE"10%"
MATERIAL"X7S"
PACK_TYPE"C0201"
VALUE"0.1UF"
CDS_LIB"pure_quanta"
PART_NUMBER"CH4102K6E00";
"B"
$PN"2"4;
"A"
$PN"1"3;
%"Q_CAP"
"1","(-2475,4375)","0","pure_quanta","I86";
;
LOCATION"C1040"
$SEC"1"
CDS_SEC"1"
PACK_TYPE"C0402"
VALUE"22UF"
TOLERANCE"20%"
VOLTAGE"4V"
MATERIAL"X6S"
CDS_LIB"pure_quanta"
PART_NUMBER"CH622KMEB02";
"B"
$PN"2"2;
"A"
$PN"1"1;
%"Q_CAP"
"1","(-3175,3750)","0","pure_quanta","I87";
;
LOCATION"C1045"
$SEC"1"
CDS_SEC"1"
VALUE"4.7UF"
MATERIAL"X6S"
TOLERANCE"20%"
VOLTAGE"6.3V"
PACK_TYPE"0402"
CDS_LIB"pure_quanta"
PART_NUMBER"CH5471MEB01";
"B"
$PN"2"2;
"A"
$PN"1"1;
%"Q_INDUCTOR"
"1","(-8375,4300)","3","pure_quanta","I88";
;
LOCATION"L30"
$SEC"1"
CDS_SEC"1"
VALUE"BLM15PD121SN1D/1300MA"
PACK_TYPE"SMLF"
MATERIAL"IND"
CDS_LIB"pure_quanta"
NEEDS_NO_SIZE"TRUE"
PART_NUMBER"CX5PD121000";
"1"
$PN"1"5;
"2"
$PN"2"13;
%"Q_RES"
"2","(-8250,4275)","0","pure_quanta","I89";
;
LOCATION"R1093"
$SEC"1"
CDS_SEC"1"
WATTAGE"1/16W"
MATERIAL"EMPTY"
PACK_TYPE"0402LF"
TOLERANCE"5%"
VALUE"0"
CDS_LIB"pure_quanta"
PART_NUMBER"CS00002JB13";
"A"
$PN"1"5;
"B"
$PN"2"13;
%"Q_CAP"
"1","(-2925,1325)","0","pure_quanta","I90";
;
LOCATION"C1018"
$SEC"1"
CDS_SEC"1"
PACK_TYPE"0201"
MATERIAL"X6S"
TOLERANCE"20%"
VOLTAGE"4V"
VALUE"1UF"
CDS_LIB"pure_quanta"
PART_NUMBER"CH-10KMEE00";
"B"
$PN"2"12;
"A"
$PN"1"11;
%"Q_CAP"
"1","(-2625,1325)","0","pure_quanta","I91";
;
LOCATION"C1020"
$SEC"1"
CDS_SEC"1"
VOLTAGE"4V"
VALUE"1UF"
MATERIAL"X6S"
PACK_TYPE"0201"
TOLERANCE"20%"
CDS_LIB"pure_quanta"
PART_NUMBER"CH-10KMEE00";
"B"
$PN"2"12;
"A"
$PN"1"11;
%"Q_CAP"
"1","(-2000,3100)","0","pure_quanta","I92";
;
LOCATION"C1051"
$SEC"1"
CDS_SEC"1"
TOLERANCE"10%"
VOLTAGE"10V"
MATERIAL"X7S"
VALUE"0.1UF"
PACK_TYPE"C0201"
CDS_LIB"pure_quanta"
PART_NUMBER"CH4102K6E00";
"B"
$PN"2"2;
"A"
$PN"1"1;
%"Q_CAP"
"1","(-1750,3100)","0","pure_quanta","I93";
;
LOCATION"C1053"
$SEC"1"
CDS_SEC"1"
VOLTAGE"10V"
VALUE"0.1UF"
TOLERANCE"10%"
MATERIAL"X7S"
PACK_TYPE"C0201"
CDS_LIB"pure_quanta"
PART_NUMBER"CH4102K6E00";
"B"
$PN"2"2;
"A"
$PN"1"1;
%"Q_CAPP"
"1","(-1200,2450)","0","pure_quanta","I94";
;
LOCATION"C7017"
$SEC"1"
CDS_SEC"1"
VALUE"470UF"
TOLERANCE"20%"
PACK_TYPE"SMLF"
VOLTAGE"2.5V"
MATERIAL"SPCAP"
CDS_LIB"pure_quanta"
PART_NUMBER"CH747LM8818";
"A"
$PN"1"1;
"B"
$PN"2"9;
%"Q_CAPP"
"1","(-900,2450)","0","pure_quanta","I95";
;
LOCATION"C7018"
$SEC"1"
CDS_SEC"1"
VOLTAGE"2.5V"
PACK_TYPE"SMLF"
MATERIAL"SPCAP"
TOLERANCE"20%"
VALUE"470UF"
CDS_LIB"pure_quanta"
PART_NUMBER"CH747LM8818";
"A"
$PN"1"1;
"B"
$PN"2"9;
%"Q_CAP"
"1","(-600,2450)","0","pure_quanta","I96";
;
LOCATION"C7019"
$SEC"1"
CDS_SEC"1"
VOLTAGE"4V"
VALUE"100UF"
PACK_TYPE"C0805"
MATERIAL"X6S"
TOLERANCE"20%"
CDS_LIB"pure_quanta"
PART_NUMBER"CH710KMEA01";
"B"
$PN"2"9;
"A"
$PN"1"1;
END.
